# S9S_MB_2U (Grand Teton) — schematic netlist excerpt (pin names and nets, part order shuffled) for the footprints in the layout excerpt that follows; sources: Cadence DE-HDL packaged netlist, KiCad conversion of 03242023_DA0F0TMBIJ0_F0T_Motherboard_J_brd_V01_OCP.brd

R223  Q_RES  1K 1% CHIP  pkg 0402LF  page 296 : A = P3V3_AUX ; B = IRQ_PVCCD_CPU1_VRHOT_LVC3_N
R2662  Q_RES  33.2 1% CHIP  pkg 0402LF  page 213 : A = FM_GPU_PWR_EN ; B = FM_GPU_PWR_EN_R

(kicad_pcb
	(version 20260206)
	(generator "pcbnew")
	(generator_version "10.0")
	(general
		(thickness 1.6)
		(legacy_teardrops no)
	)
	(paper "A4")
	(title_block
		(title "03242023_DA0F0TMBIJ0_F0T_Motherboard_J_brd_V01_OCP.brd")
		(comment 1 "Grand Teton / footprints 1492-1493 of 6105")
	)
	(layers
		(0 "F.Cu" signal "TOP")
		(4 "In1.Cu" signal "GND")
		(6 "In2.Cu" signal "IN1")
		(8 "In3.Cu" signal "GND1")
		(10 "In4.Cu" signal "IN2")
		(12 "In5.Cu" signal "GND2")
		(14 "In6.Cu" signal "IN3")
		(16 "In7.Cu" signal "GND3")
		(18 "In8.Cu" signal "VCC")
		(20 "In9.Cu" signal "VCC1")
		(22 "In10.Cu" signal "GND4")
		(24 "In11.Cu" signal "IN4")
		(26 "In12.Cu" signal "GND5")
		(28 "In13.Cu" signal "IN5")
		(30 "In14.Cu" signal "GND6")
		(32 "In15.Cu" signal "IN6")
		(34 "In16.Cu" signal "GND7")
		(2 "B.Cu" signal "BOTTOM")
		(9 "F.Adhes" user "F.Adhesive")
		(11 "B.Adhes" user "B.Adhesive")
		(13 "F.Paste" user "Package Geometry/Pastemask Top")
		(15 "B.Paste" user "Package Geometry/Pastemask Bottom")
		(5 "F.SilkS" user "Ref Des/Silkscreen Top")
		(7 "B.SilkS" user "Ref Des/Silkscreen Bottom")
		(1 "F.Mask" user "Board Geometry/Soldermask Top")
		(3 "B.Mask" user "Board Geometry/Soldermask Bottom")
		(17 "Dwgs.User" user "User.Drawings")
		(19 "Cmts.User" user "User.Comments")
		(21 "Eco1.User" user "User.Eco1")
		(23 "Eco2.User" user "User.Eco2")
		(25 "Edge.Cuts" user "Board Geometry/Outline")
		(27 "Margin" user)
		(31 "F.CrtYd" user "Package Geometry/Place Bound Top")
		(29 "B.CrtYd" user "Package Geometry/Place Bound Bottom")
		(35 "F.Fab" user "Ref Des/Assembly Top")
		(33 "B.Fab" user "Ref Des/Assembly Bottom")
	)
	(footprint ""
		(layer "F.Cu")
		(at 164.64788 -104.485948 180)
		(property "Reference" "R2662"
			(at 0 0 180)
			(layer "F.SilkS")
			(hide yes)
			(effects
				(font
					(size 1.27 1.27)
				)
			)
		)
		(property "Value" ""
			(at 0 0 180)
			(layer "F.Fab")
			(effects
				(font
					(size 1.27 1.27)
				)
			)
		)
		(duplicate_pad_numbers_are_jumpers no)
		(fp_line
			(start 0.7874 0.4064)
			(end -0.7874 0.4064)
			(stroke
				(width 0.1524)
				(type default)
			)
			(layer "F.SilkS")
		)
		(fp_line
			(start 0.7874 -0.4064)
			(end 0.7874 0.4064)
			(stroke
				(width 0.1524)
				(type default)
			)
			(layer "F.SilkS")
		)
		(fp_line
			(start -0.7874 0.4064)
			(end -0.7874 -0.4064)
			(stroke
				(width 0.1524)
				(type default)
			)
			(layer "F.SilkS")
		)
		(fp_line
			(start -0.7874 -0.4064)
			(end 0.7874 -0.4064)
			(stroke
				(width 0.1524)
				(type default)
			)
			(layer "F.SilkS")
		)
		(fp_line
			(start 0.67945 0.3048)
			(end 0.120396 0.3048)
			(stroke
				(width 0.1)
				(type default)
			)
			(layer "F.Fab")
		)
		(fp_line
			(start 0.67945 -0.3048)
			(end 0.67945 0.3048)
			(stroke
				(width 0.1)
				(type default)
			)
			(layer "F.Fab")
		)
		(fp_line
			(start 0.12065 -0.2794)
			(end 0.12065 -0.3048)
			(stroke
				(width 0.1)
				(type default)
			)
			(layer "F.Fab")
		)
		(fp_line
			(start 0.12065 -0.3048)
			(end 0.67945 -0.3048)
			(stroke
				(width 0.1)
				(type default)
			)
			(layer "F.Fab")
		)
		(fp_line
			(start 0.120396 0.3048)
			(end 0.120396 0.2794)
			(stroke
				(width 0.1)
				(type default)
			)
			(layer "F.Fab")
		)
		(fp_line
			(start 0.120396 0.2794)
			(end -0.12065 0.2794)
			(stroke
				(width 0.1)
				(type default)
			)
			(layer "F.Fab")
		)
		(fp_line
			(start -0.12065 0.3048)
			(end -0.67945 0.3048)
			(stroke
				(width 0.1)
				(type default)
			)
			(layer "F.Fab")
		)
		(fp_line
			(start -0.12065 0.2794)
			(end -0.12065 0.3048)
			(stroke
				(width 0.1)
				(type default)
			)
			(layer "F.Fab")
		)
		(fp_line
			(start -0.12065 -0.2794)
			(end 0.12065 -0.2794)
			(stroke
				(width 0.1)
				(type default)
			)
			(layer "F.Fab")
		)
		(fp_line
			(start -0.12065 -0.305054)
			(end -0.12065 -0.2794)
			(stroke
				(width 0.1)
				(type default)
			)
			(layer "F.Fab")
		)
		(fp_line
			(start -0.67945 0.3048)
			(end -0.67945 -0.305054)
			(stroke
				(width 0.1)
				(type default)
			)
			(layer "F.Fab")
		)
		(fp_line
			(start -0.67945 -0.305054)
			(end -0.12065 -0.305054)
			(stroke
				(width 0.1)
				(type default)
			)
			(layer "F.Fab")
		)
		(pad "1" smd circle
			(at -0.40005 0 180)
			(size 0 0)
			(layers "F.Cu" "F.Mask" "F.Paste")
			(net "FM_GPU_PWR_EN")
		)
		(pad "2" smd circle
			(at 0.40005 0 180)
			(size 0 0)
			(layers "F.Cu" "F.Mask" "F.Paste")
			(net "FM_GPU_PWR_EN_R")
		)
	)
	(footprint ""
		(layer "F.Cu")
		(at 21.73351 -168.183306 90)
		(property "Reference" "R223"
			(at 0 0 90)
			(layer "F.SilkS")
			(hide yes)
			(effects
				(font
					(size 1.27 1.27)
				)
			)
		)
		(property "Value" ""
			(at 0 0 90)
			(layer "F.Fab")
			(effects
				(font
					(size 1.27 1.27)
				)
			)
		)
		(duplicate_pad_numbers_are_jumpers no)
		(fp_line
			(start 0.7874 -0.4064)
			(end 0.7874 0.4064)
			(stroke
				(width 0.1524)
				(type default)
			)
			(layer "F.SilkS")
		)
		(fp_line
			(start -0.7874 -0.4064)
			(end 0.7874 -0.4064)
			(stroke
				(width 0.1524)
				(type default)
			)
			(layer "F.SilkS")
		)
		(fp_line
			(start 0.7874 0.4064)
			(end -0.7874 0.4064)
			(stroke
				(width 0.1524)
				(type default)
			)
			(layer "F.SilkS")
		)
		(fp_line
			(start -0.7874 0.4064)
			(end -0.7874 -0.4064)
			(stroke
				(width 0.1524)
				(type default)
			)
			(layer "F.SilkS")
		)
		(fp_line
			(start -0.12065 -0.305054)
			(end -0.12065 -0.2794)
			(stroke
				(width 0.1)
				(type default)
			)
			(layer "F.Fab")
		)
		(fp_line
			(start -0.67945 -0.305054)
			(end -0.12065 -0.305054)
			(stroke
				(width 0.1)
				(type default)
			)
			(layer "F.Fab")
		)
		(fp_line
			(start 0.67945 -0.3048)
			(end 0.67945 0.3048)
			(stroke
				(width 0.1)
				(type default)
			)
			(layer "F.Fab")
		)
		(fp_line
			(start 0.12065 -0.3048)
			(end 0.67945 -0.3048)
			(stroke
				(width 0.1)
				(type default)
			)
			(layer "F.Fab")
		)
		(fp_line
			(start 0.12065 -0.2794)
			(end 0.12065 -0.3048)
			(stroke
				(width 0.1)
				(type default)
			)
			(layer "F.Fab")
		)
		(fp_line
			(start -0.12065 -0.2794)
			(end 0.12065 -0.2794)
			(stroke
				(width 0.1)
				(type default)
			)
			(layer "F.Fab")
		)
		(fp_line
			(start 0.120396 0.2794)
			(end -0.12065 0.2794)
			(stroke
				(width 0.1)
				(type default)
			)
			(layer "F.Fab")
		)
		(fp_line
			(start -0.12065 0.2794)
			(end -0.12065 0.3048)
			(stroke
				(width 0.1)
				(type default)
			)
			(layer "F.Fab")
		)
		(fp_line
			(start 0.67945 0.3048)
			(end 0.120396 0.3048)
			(stroke
				(width 0.1)
				(type default)
			)
			(layer "F.Fab")
		)
		(fp_line
			(start 0.120396 0.3048)
			(end 0.120396 0.2794)
			(stroke
				(width 0.1)
				(type default)
			)
			(layer "F.Fab")
		)
		(fp_line
			(start -0.12065 0.3048)
			(end -0.67945 0.3048)
			(stroke
				(width 0.1)
				(type default)
			)
			(layer "F.Fab")
		)
		(fp_line
			(start -0.67945 0.3048)
			(end -0.67945 -0.305054)
			(stroke
				(width 0.1)
				(type default)
			)
			(layer "F.Fab")
		)
		(pad "1" smd circle
			(at -0.40005 0 90)
			(size 0 0)
			(layers "F.Cu" "F.Mask" "F.Paste")
			(net "P3V3_AUX")
		)
		(pad "2" smd circle
			(at 0.40005 0 90)
			(size 0 0)
			(layers "F.Cu" "F.Mask" "F.Paste")
			(net "IRQ_PVCCD_CPU1_VRHOT_LVC3_N")
		)
	)
)
